(kicad_pcb
	(version 20260206)
	(generator "pcbnew")
	(generator_version "10.0")
	(general
		(thickness 1.6)
		(legacy_teardrops no)
	)
	(paper "A4")
	(title_block
		(title "peb — Lightning_PEB_BRD.brd")
		(comment 1 "Lightning (Wiwynn / Facebook NVMe JBOF) / footprints 1799-1806 of 2563")
	)
	(layers
		(0 "F.Cu" signal "TOP")
		(4 "In1.Cu" signal "L2GND")
		(6 "In2.Cu" signal "L3")
		(8 "In3.Cu" signal "L4VCC")
		(10 "In4.Cu" signal "L5VCC")
		(12 "In5.Cu" signal "L6")
		(14 "In6.Cu" signal "L7GND")
		(2 "B.Cu" signal "BOTTOM")
		(9 "F.Adhes" user "F.Adhesive")
		(11 "B.Adhes" user "B.Adhesive")
		(13 "F.Paste" user "Package Geometry/Pastemask Top")
		(15 "B.Paste" user "Package Geometry/Pastemask Bottom")
		(5 "F.SilkS" user "Ref Des/Silkscreen Top")
		(7 "B.SilkS" user "Ref Des/Silkscreen Bottom")
		(1 "F.Mask" user "Board Geometry/Soldermask Top")
		(3 "B.Mask" user "Board Geometry/Soldermask Bottom")
		(17 "Dwgs.User" user "User.Drawings")
		(19 "Cmts.User" user "User.Comments")
		(21 "Eco1.User" user "User.Eco1")
		(23 "Eco2.User" user "User.Eco2")
		(25 "Edge.Cuts" user "Board Geometry/Outline")
		(27 "Margin" user)
		(31 "F.CrtYd" user "Package Geometry/Place Bound Top")
		(29 "B.CrtYd" user "Package Geometry/Place Bound Bottom")
		(35 "F.Fab" user "Ref Des/Assembly Top")
		(33 "B.Fab" user "Ref Des/Assembly Bottom")
	)
	(footprint ""
		(layer "B.Cu")
		(at 241.681 -20.447)
		(property "Reference" "R811"
			(at 0 0 0)
			(layer "B.SilkS")
			(hide yes)
			(effects
				(font
					(size 1.27 1.27)
				)
				(justify mirror)
			)
		)
		(property "Value" "4K7R2F-GP"
			(at -0.064008 -3.993896 0)
			(unlocked yes)
			(layer "B.Fab")
			(hide yes)
			(effects
				(font
					(size 1.016 1.016)
					(thickness 0.1524)
				)
				(justify mirror)
			)
		)
		(property "Device Type" "R402H16"
			(at -0.064008 -5.517896 0)
			(unlocked yes)
			(layer "B.Fab")
			(hide yes)
			(effects
				(font
					(size 1.016 1.016)
					(thickness 0.1524)
				)
				(justify mirror)
			)
		)
		(duplicate_pad_numbers_are_jumpers no)
		(fp_line
			(start -0.508 -0.9398)
			(end 0.508 -0.9398)
			(stroke
				(width 0.1524)
				(type default)
			)
			(layer "B.SilkS")
		)
		(fp_line
			(start 0.508 -0.9398)
			(end 0.508 0.9398)
			(stroke
				(width 0.1524)
				(type default)
			)
			(layer "B.SilkS")
		)
		(fp_rect
			(start 0.508 0.9398)
			(end -0.508 -0.9398)
			(stroke
				(width 0)
				(type default)
			)
			(fill no)
			(layer "B.CrtYd")
		)
		(fp_rect
			(start 0.508 0.9398)
			(end -0.508 -0.9398)
			(stroke
				(width 0)
				(type default)
			)
			(fill no)
			(layer "B.Fab")
		)
		(pad "1" smd custom
			(at 0 -0.4445 180)
			(size 0.1397 0.1397)
			(layers "B.Cu" "B.Mask" "B.Paste")
			(net "BOOTSTRAP5")
			(options
				(clearance outline)
				(anchor circle)
			)
			(primitives
				(gr_poly
					(pts
						(arc
							(start -0.1778 0.2794)
							(mid -0.249642 0.249642)
							(end -0.2794 0.1778)
						)
						(arc
							(start -0.2794 -0.1778)
							(mid -0.249642 -0.249642)
							(end -0.1778 -0.2794)
						)
						(arc
							(start 0.1778 -0.2794)
							(mid 0.249642 -0.249642)
							(end 0.2794 -0.1778)
						)
						(arc
							(start 0.2794 0.1778)
							(mid 0.249642 0.249642)
							(end 0.1778 0.2794)
						)
					)
					(width 0)
					(fill yes)
				)
			)
		)
		(pad "2" smd custom
			(at 0 0.4445 180)
			(size 0.1397 0.1397)
			(layers "B.Cu" "B.Mask" "B.Paste")
			(net "DUT_VDDO")
			(options
				(clearance outline)
				(anchor circle)
			)
			(primitives
				(gr_poly
					(pts
						(arc
							(start -0.1778 0.2794)
							(mid -0.249642 0.249642)
							(end -0.2794 0.1778)
						)
						(arc
							(start -0.2794 -0.1778)
							(mid -0.249642 -0.249642)
							(end -0.1778 -0.2794)
						)
						(arc
							(start 0.1778 -0.2794)
							(mid 0.249642 -0.249642)
							(end 0.2794 -0.1778)
						)
						(arc
							(start 0.2794 0.1778)
							(mid 0.249642 0.249642)
							(end 0.1778 0.2794)
						)
					)
					(width 0)
					(fill yes)
				)
			)
		)
	)
	(footprint ""
		(layer "B.Cu")
		(at 57.023 -139.827 -90)
		(property "Reference" "R310"
			(at 0 0 90)
			(layer "B.SilkS")
			(hide yes)
			(effects
				(font
					(size 1.27 1.27)
				)
				(justify mirror)
			)
		)
		(property "Value" "0R2J-2-GP"
			(at -0.064008 -3.993896 270)
			(unlocked yes)
			(layer "B.Fab")
			(hide yes)
			(effects
				(font
					(size 1.016 1.016)
					(thickness 0.1524)
				)
				(justify mirror)
			)
		)
		(property "Device Type" "R402H16"
			(at -0.064008 -5.517896 270)
			(unlocked yes)
			(layer "B.Fab")
			(hide yes)
			(effects
				(font
					(size 1.016 1.016)
					(thickness 0.1524)
				)
				(justify mirror)
			)
		)
		(duplicate_pad_numbers_are_jumpers no)
		(fp_line
			(start -0.508 -0.9398)
			(end 0.508 -0.9398)
			(stroke
				(width 0.1524)
				(type default)
			)
			(layer "B.SilkS")
		)
		(fp_line
			(start 0.508 -0.9398)
			(end 0.508 0.9398)
			(stroke
				(width 0.1524)
				(type default)
			)
			(layer "B.SilkS")
		)
		(fp_rect
			(start 0.508 0.9398)
			(end -0.508 -0.9398)
			(stroke
				(width 0)
				(type default)
			)
			(fill no)
			(layer "B.CrtYd")
		)
		(fp_rect
			(start 0.508 0.9398)
			(end -0.508 -0.9398)
			(stroke
				(width 0)
				(type default)
			)
			(fill no)
			(layer "B.Fab")
		)
		(pad "1" smd custom
			(at 0 -0.4445 90)
			(size 0.1397 0.1397)
			(layers "B.Cu" "B.Mask" "B.Paste")
			(net "BMC_SELF_TRAY")
			(options
				(clearance outline)
				(anchor circle)
			)
			(primitives
				(gr_poly
					(pts
						(arc
							(start -0.1778 0.2794)
							(mid -0.249642 0.249642)
							(end -0.2794 0.1778)
						)
						(arc
							(start -0.2794 -0.1778)
							(mid -0.249642 -0.249642)
							(end -0.1778 -0.2794)
						)
						(arc
							(start 0.1778 -0.2794)
							(mid 0.249642 -0.249642)
							(end 0.2794 -0.1778)
						)
						(arc
							(start 0.2794 0.1778)
							(mid 0.249642 0.249642)
							(end 0.1778 0.2794)
						)
					)
					(width 0)
					(fill yes)
				)
			)
		)
		(pad "2" smd custom
			(at 0 0.4445 90)
			(size 0.1397 0.1397)
			(layers "B.Cu" "B.Mask" "B.Paste")
			(net "BMC_SELF_TRAY_R")
			(options
				(clearance outline)
				(anchor circle)
			)
			(primitives
				(gr_poly
					(pts
						(arc
							(start -0.1778 0.2794)
							(mid -0.249642 0.249642)
							(end -0.2794 0.1778)
						)
						(arc
							(start -0.2794 -0.1778)
							(mid -0.249642 -0.249642)
							(end -0.1778 -0.2794)
						)
						(arc
							(start 0.1778 -0.2794)
							(mid 0.249642 -0.249642)
							(end 0.2794 -0.1778)
						)
						(arc
							(start 0.2794 0.1778)
							(mid 0.249642 0.249642)
							(end 0.1778 0.2794)
						)
					)
					(width 0)
					(fill yes)
				)
			)
		)
	)
	(footprint ""
		(layer "B.Cu")
		(at 236.5629 -40.005 90)
		(property "Reference" "C547"
			(at 0 0 90)
			(layer "B.SilkS")
			(hide yes)
			(effects
				(font
					(size 1.27 1.27)
				)
				(justify mirror)
			)
		)
		(property "Value" "SCD1U16V1KX-1-GP"
			(at 2.8321 -1.7399 90)
			(unlocked yes)
			(layer "B.Fab")
			(hide yes)
			(effects
				(font
					(size 1.016 1.016)
					(thickness 0.1524)
				)
				(justify mirror)
			)
		)
		(property "Device Type" "C0201H13"
			(at 2.8321 -3.2639 90)
			(unlocked yes)
			(layer "B.Fab")
			(hide yes)
			(effects
				(font
					(size 1.016 1.016)
					(thickness 0.1524)
				)
				(justify mirror)
			)
		)
		(duplicate_pad_numbers_are_jumpers no)
		(fp_rect
			(start 0.2794 0.6477)
			(end -0.2794 -0.6477)
			(stroke
				(width 0)
				(type default)
			)
			(fill no)
			(layer "B.CrtYd")
		)
		(fp_rect
			(start 0.2794 0.6477)
			(end -0.2794 -0.6477)
			(stroke
				(width 0)
				(type default)
			)
			(fill no)
			(layer "B.Fab")
		)
		(pad "1" smd custom
			(at 0 -0.2794 270)
			(size 0.0762 0.0762)
			(layers "B.Cu" "B.Mask" "B.Paste")
			(net "DUT_AVD_PCIE")
			(options
				(clearance outline)
				(anchor circle)
			)
			(primitives
				(gr_poly
					(pts
						(arc
							(start 0.1524 0.127)
							(mid 0.137521 0.162921)
							(end 0.1016 0.1778)
						)
						(arc
							(start -0.1016 0.1778)
							(mid -0.137521 0.162921)
							(end -0.1524 0.127)
						)
						(arc
							(start -0.1524 -0.127)
							(mid -0.137521 -0.162921)
							(end -0.1016 -0.1778)
						)
						(arc
							(start 0.1016 -0.1778)
							(mid 0.137521 -0.162921)
							(end 0.1524 -0.127)
						)
					)
					(width 0)
					(fill yes)
				)
			)
		)
		(pad "2" smd custom
			(at 0 0.2794 270)
			(size 0.0762 0.0762)
			(layers "B.Cu" "B.Mask" "B.Paste")
			(net "GND")
			(options
				(clearance outline)
				(anchor circle)
			)
			(primitives
				(gr_poly
					(pts
						(arc
							(start 0.1524 0.127)
							(mid 0.137521 0.162921)
							(end 0.1016 0.1778)
						)
						(arc
							(start -0.1016 0.1778)
							(mid -0.137521 0.162921)
							(end -0.1524 0.127)
						)
						(arc
							(start -0.1524 -0.127)
							(mid -0.137521 -0.162921)
							(end -0.1016 -0.1778)
						)
						(arc
							(start 0.1016 -0.1778)
							(mid 0.137521 -0.162921)
							(end 0.1524 -0.127)
						)
					)
					(width 0)
					(fill yes)
				)
			)
		)
	)
	(footprint ""
		(layer "B.Cu")
		(at 249.588528 -39.99992 -90)
		(property "Reference" "TP209"
			(at 0 0 90)
			(layer "B.SilkS")
			(hide yes)
			(effects
				(font
					(size 1.27 1.27)
				)
				(justify mirror)
			)
		)
		(property "Value" "TPAD28-2-GP"
			(at 0.0127 -1.6637 270)
			(unlocked yes)
			(layer "B.Fab")
			(hide yes)
			(effects
				(font
					(size 1.016 1.016)
					(thickness 0.1524)
				)
				(justify mirror)
			)
		)
		(property "Device Type" "TPAD28"
			(at 0.0127 -3.1877 270)
			(unlocked yes)
			(layer "B.Fab")
			(hide yes)
			(effects
				(font
					(size 1.016 1.016)
					(thickness 0.1524)
				)
				(justify mirror)
			)
		)
		(duplicate_pad_numbers_are_jumpers no)
		(fp_poly
			(pts
				(arc
					(start 0 -0.3556)
					(mid 0 0.3556)
					(end 0 -0.3556)
				)
			)
			(stroke
				(width 0)
				(type default)
			)
			(fill no)
			(layer "B.CrtYd")
		)
		(fp_poly
			(pts
				(arc
					(start 0 -0.6096)
					(mid 0 0.6096)
					(end 0 -0.6096)
				)
			)
			(stroke
				(width 0)
				(type default)
			)
			(fill no)
			(layer "B.Fab")
		)
		(pad "1" smd circle
			(at 0 0 90)
			(size 0.7112 0.7112)
			(layers "B.Cu" "B.Mask" "B.Paste")
			(net "GPIO108_R")
		)
	)
	(footprint ""
		(layer "B.Cu")
		(at 246.888 -37.9984 90)
		(property "Reference" "C483"
			(at 0 0 90)
			(layer "B.SilkS")
			(hide yes)
			(effects
				(font
					(size 1.27 1.27)
				)
				(justify mirror)
			)
		)
		(property "Value" "SCD1U16V1KX-1-GP"
			(at 2.8321 -1.7399 90)
			(unlocked yes)
			(layer "B.Fab")
			(hide yes)
			(effects
				(font
					(size 1.016 1.016)
					(thickness 0.1524)
				)
				(justify mirror)
			)
		)
		(property "Device Type" "C0201H13"
			(at 2.8321 -3.2639 90)
			(unlocked yes)
			(layer "B.Fab")
			(hide yes)
			(effects
				(font
					(size 1.016 1.016)
					(thickness 0.1524)
				)
				(justify mirror)
			)
		)
		(duplicate_pad_numbers_are_jumpers no)
		(fp_rect
			(start 0.2794 0.6477)
			(end -0.2794 -0.6477)
			(stroke
				(width 0)
				(type default)
			)
			(fill no)
			(layer "B.CrtYd")
		)
		(fp_rect
			(start 0.2794 0.6477)
			(end -0.2794 -0.6477)
			(stroke
				(width 0)
				(type default)
			)
			(fill no)
			(layer "B.Fab")
		)
		(pad "1" smd custom
			(at 0 -0.2794 270)
			(size 0.0762 0.0762)
			(layers "B.Cu" "B.Mask" "B.Paste")
			(net "DUT_VDDO")
			(options
				(clearance outline)
				(anchor circle)
			)
			(primitives
				(gr_poly
					(pts
						(arc
							(start 0.1524 0.127)
							(mid 0.137521 0.162921)
							(end 0.1016 0.1778)
						)
						(arc
							(start -0.1016 0.1778)
							(mid -0.137521 0.162921)
							(end -0.1524 0.127)
						)
						(arc
							(start -0.1524 -0.127)
							(mid -0.137521 -0.162921)
							(end -0.1016 -0.1778)
						)
						(arc
							(start 0.1016 -0.1778)
							(mid 0.137521 -0.162921)
							(end 0.1524 -0.127)
						)
					)
					(width 0)
					(fill yes)
				)
			)
		)
		(pad "2" smd custom
			(at 0 0.2794 270)
			(size 0.0762 0.0762)
			(layers "B.Cu" "B.Mask" "B.Paste")
			(net "GND")
			(options
				(clearance outline)
				(anchor circle)
			)
			(primitives
				(gr_poly
					(pts
						(arc
							(start 0.1524 0.127)
							(mid 0.137521 0.162921)
							(end 0.1016 0.1778)
						)
						(arc
							(start -0.1016 0.1778)
							(mid -0.137521 0.162921)
							(end -0.1524 0.127)
						)
						(arc
							(start -0.1524 -0.127)
							(mid -0.137521 -0.162921)
							(end -0.1016 -0.1778)
						)
						(arc
							(start 0.1016 -0.1778)
							(mid 0.137521 -0.162921)
							(end 0.1524 -0.127)
						)
					)
					(width 0)
					(fill yes)
				)
			)
		)
	)
	(footprint ""
		(layer "B.Cu")
		(at 132.54228 -33.54578)
		(property "Reference" "R2926"
			(at 0 0 0)
			(layer "B.SilkS")
			(hide yes)
			(effects
				(font
					(size 1.27 1.27)
				)
				(justify mirror)
			)
		)
		(property "Value" "0R2J-2-GP"
			(at -0.064008 -3.993896 0)
			(unlocked yes)
			(layer "B.Fab")
			(hide yes)
			(effects
				(font
					(size 1.016 1.016)
					(thickness 0.1524)
				)
				(justify mirror)
			)
		)
		(property "Device Type" "R402H16"
			(at -0.064008 -5.517896 0)
			(unlocked yes)
			(layer "B.Fab")
			(hide yes)
			(effects
				(font
					(size 1.016 1.016)
					(thickness 0.1524)
				)
				(justify mirror)
			)
		)
		(duplicate_pad_numbers_are_jumpers no)
		(fp_line
			(start -0.508 -0.9398)
			(end 0.508 -0.9398)
			(stroke
				(width 0.1524)
				(type default)
			)
			(layer "B.SilkS")
		)
		(fp_line
			(start 0.508 -0.9398)
			(end 0.508 0.9398)
			(stroke
				(width 0.1524)
				(type default)
			)
			(layer "B.SilkS")
		)
		(fp_rect
			(start 0.508 0.9398)
			(end -0.508 -0.9398)
			(stroke
				(width 0)
				(type default)
			)
			(fill no)
			(layer "B.CrtYd")
		)
		(fp_rect
			(start 0.508 0.9398)
			(end -0.508 -0.9398)
			(stroke
				(width 0)
				(type default)
			)
			(fill no)
			(layer "B.Fab")
		)
		(pad "1" smd custom
			(at 0 -0.4445 180)
			(size 0.1397 0.1397)
			(layers "B.Cu" "B.Mask" "B.Paste")
			(net "BMC_I2C1_MINI1_SDA")
			(options
				(clearance outline)
				(anchor circle)
			)
			(primitives
				(gr_poly
					(pts
						(arc
							(start -0.1778 0.2794)
							(mid -0.249642 0.249642)
							(end -0.2794 0.1778)
						)
						(arc
							(start -0.2794 -0.1778)
							(mid -0.249642 -0.249642)
							(end -0.1778 -0.2794)
						)
						(arc
							(start 0.1778 -0.2794)
							(mid 0.249642 -0.249642)
							(end 0.2794 -0.1778)
						)
						(arc
							(start 0.2794 0.1778)
							(mid 0.249642 0.249642)
							(end 0.1778 0.2794)
						)
					)
					(width 0)
					(fill yes)
				)
			)
		)
		(pad "2" smd custom
			(at 0 0.4445 180)
			(size 0.1397 0.1397)
			(layers "B.Cu" "B.Mask" "B.Paste")
			(net "8644_CBL_PRSNT_R_1")
			(options
				(clearance outline)
				(anchor circle)
			)
			(primitives
				(gr_poly
					(pts
						(arc
							(start -0.1778 0.2794)
							(mid -0.249642 0.249642)
							(end -0.2794 0.1778)
						)
						(arc
							(start -0.2794 -0.1778)
							(mid -0.249642 -0.249642)
							(end -0.1778 -0.2794)
						)
						(arc
							(start 0.1778 -0.2794)
							(mid 0.249642 -0.249642)
							(end 0.2794 -0.1778)
						)
						(arc
							(start 0.2794 0.1778)
							(mid 0.249642 0.249642)
							(end 0.1778 0.2794)
						)
					)
					(width 0)
					(fill yes)
				)
			)
		)
	)
	(footprint ""
		(layer "B.Cu")
		(at 245.1354 -47.032672 -90)
		(property "Reference" "C461"
			(at 0 0 90)
			(layer "B.SilkS")
			(hide yes)
			(effects
				(font
					(size 1.27 1.27)
				)
				(justify mirror)
			)
		)
		(property "Value" "SCD1U16V1KX-1-GP"
			(at 2.8321 -1.7399 270)
			(unlocked yes)
			(layer "B.Fab")
			(hide yes)
			(effects
				(font
					(size 1.016 1.016)
					(thickness 0.1524)
				)
				(justify mirror)
			)
		)
		(property "Device Type" "C0201H13"
			(at 2.8321 -3.2639 270)
			(unlocked yes)
			(layer "B.Fab")
			(hide yes)
			(effects
				(font
					(size 1.016 1.016)
					(thickness 0.1524)
				)
				(justify mirror)
			)
		)
		(duplicate_pad_numbers_are_jumpers no)
		(fp_rect
			(start 0.2794 0.6477)
			(end -0.2794 -0.6477)
			(stroke
				(width 0)
				(type default)
			)
			(fill no)
			(layer "B.CrtYd")
		)
		(fp_rect
			(start 0.2794 0.6477)
			(end -0.2794 -0.6477)
			(stroke
				(width 0)
				(type default)
			)
			(fill no)
			(layer "B.Fab")
		)
		(pad "1" smd custom
			(at 0 -0.2794 90)
			(size 0.0762 0.0762)
			(layers "B.Cu" "B.Mask" "B.Paste")
			(net "DUT_VDD")
			(options
				(clearance outline)
				(anchor circle)
			)
			(primitives
				(gr_poly
					(pts
						(arc
							(start 0.1524 0.127)
							(mid 0.137521 0.162921)
							(end 0.1016 0.1778)
						)
						(arc
							(start -0.1016 0.1778)
							(mid -0.137521 0.162921)
							(end -0.1524 0.127)
						)
						(arc
							(start -0.1524 -0.127)
							(mid -0.137521 -0.162921)
							(end -0.1016 -0.1778)
						)
						(arc
							(start 0.1016 -0.1778)
							(mid 0.137521 -0.162921)
							(end 0.1524 -0.127)
						)
					)
					(width 0)
					(fill yes)
				)
			)
		)
		(pad "2" smd custom
			(at 0 0.2794 90)
			(size 0.0762 0.0762)
			(layers "B.Cu" "B.Mask" "B.Paste")
			(net "GND")
			(options
				(clearance outline)
				(anchor circle)
			)
			(primitives
				(gr_poly
					(pts
						(arc
							(start 0.1524 0.127)
							(mid 0.137521 0.162921)
							(end 0.1016 0.1778)
						)
						(arc
							(start -0.1016 0.1778)
							(mid -0.137521 0.162921)
							(end -0.1524 0.127)
						)
						(arc
							(start -0.1524 -0.127)
							(mid -0.137521 -0.162921)
							(end -0.1016 -0.1778)
						)
						(arc
							(start 0.1016 -0.1778)
							(mid 0.137521 -0.162921)
							(end 0.1524 -0.127)
						)
					)
					(width 0)
					(fill yes)
				)
			)
		)
	)
	(footprint ""
		(layer "B.Cu")
		(at 181.70906 -7.97052)
		(property "Reference" "R268"
			(at 0 0 0)
			(layer "B.SilkS")
			(hide yes)
			(effects
				(font
					(size 1.27 1.27)
				)
				(justify mirror)
			)
		)
		(property "Value" "0R2J-2-GP"
			(at -0.064008 -3.993896 0)
			(unlocked yes)
			(layer "B.Fab")
			(hide yes)
			(effects
				(font
					(size 1.016 1.016)
					(thickness 0.1524)
				)
				(justify mirror)
			)
		)
		(property "Device Type" "R402H16"
			(at -0.064008 -5.517896 0)
			(unlocked yes)
			(layer "B.Fab")
			(hide yes)
			(effects
				(font
					(size 1.016 1.016)
					(thickness 0.1524)
				)
				(justify mirror)
			)
		)
		(duplicate_pad_numbers_are_jumpers no)
		(fp_line
			(start -0.508 -0.9398)
			(end 0.508 -0.9398)
			(stroke
				(width 0.1524)
				(type default)
			)
			(layer "B.SilkS")
		)
		(fp_line
			(start 0.508 -0.9398)
			(end 0.508 0.9398)
			(stroke
				(width 0.1524)
				(type default)
			)
			(layer "B.SilkS")
		)
		(fp_rect
			(start 0.508 0.9398)
			(end -0.508 -0.9398)
			(stroke
				(width 0)
				(type default)
			)
			(fill no)
			(layer "B.CrtYd")
		)
		(fp_rect
			(start 0.508 0.9398)
			(end -0.508 -0.9398)
			(stroke
				(width 0)
				(type default)
			)
			(fill no)
			(layer "B.Fab")
		)
		(pad "1" smd custom
			(at 0 -0.4445 180)
			(size 0.1397 0.1397)
			(layers "B.Cu" "B.Mask" "B.Paste")
			(net "MINISAS_CN15_A_I2C_INT#")
			(options
				(clearance outline)
				(anchor circle)
			)
			(primitives
				(gr_poly
					(pts
						(arc
							(start -0.1778 0.2794)
							(mid -0.249642 0.249642)
							(end -0.2794 0.1778)
						)
						(arc
							(start -0.2794 -0.1778)
							(mid -0.249642 -0.249642)
							(end -0.1778 -0.2794)
						)
						(arc
							(start 0.1778 -0.2794)
							(mid 0.249642 -0.249642)
							(end 0.2794 -0.1778)
						)
						(arc
							(start 0.2794 0.1778)
							(mid 0.249642 0.249642)
							(end 0.1778 0.2794)
						)
					)
					(width 0)
					(fill yes)
				)
			)
		)
		(pad "2" smd custom
			(at 0 0.4445 180)
			(size 0.1397 0.1397)
			(layers "B.Cu" "B.Mask" "B.Paste")
			(net "PCIE_REFCLK_H2_N_R")
			(options
				(clearance outline)
				(anchor circle)
			)
			(primitives
				(gr_poly
					(pts
						(arc
							(start -0.1778 0.2794)
							(mid -0.249642 0.249642)
							(end -0.2794 0.1778)
						)
						(arc
							(start -0.2794 -0.1778)
							(mid -0.249642 -0.249642)
							(end -0.1778 -0.2794)
						)
						(arc
							(start 0.1778 -0.2794)
							(mid 0.249642 -0.249642)
							(end 0.2794 -0.1778)
						)
						(arc
							(start 0.2794 0.1778)
							(mid 0.249642 0.249642)
							(end 0.1778 0.2794)
						)
					)
					(width 0)
					(fill yes)
				)
			)
		)
	)
)
